# S9S_MB_2U (Grand Teton) — schematic netlist excerpt (pin names and nets, part order shuffled) for the footprints in the layout excerpt that follows; sources: Cadence DE-HDL packaged netlist, KiCad conversion of 03242023_DA0F0TMBIJ0_F0T_Motherboard_J_brd_V01_OCP.brd

R272  Q_RES  10K 1% CHIP  pkg 0402LF  page 119 : A = P3V3_AUX ; B = FM_CPU1_PKGID2

U244  NC7SB3157  NC7SB3157P6X EMPTY  pkg SMLF  page 165
  B1  = OCP_SFF_NOT_PRSNT_RBT_ARB_IN
  GND  = GND
  B0  = OCP_SFF_RBT_ARB_IN
  A  = OCP_SFF_RBT_ARB_IN_MUX1_R
  VCC  = P3V3_AUX
  S  = OCP_SFF_PRSNT_ALL_R3_N

(kicad_pcb
	(version 20260206)
	(generator "pcbnew")
	(generator_version "10.0")
	(general
		(thickness 1.6)
		(legacy_teardrops no)
	)
	(paper "A4")
	(title_block
		(title "03242023_DA0F0TMBIJ0_F0T_Motherboard_J_brd_V01_OCP.brd")
		(comment 1 "Grand Teton / footprints 1233-1234 of 6105")
	)
	(layers
		(0 "F.Cu" signal "TOP")
		(4 "In1.Cu" signal "GND")
		(6 "In2.Cu" signal "IN1")
		(8 "In3.Cu" signal "GND1")
		(10 "In4.Cu" signal "IN2")
		(12 "In5.Cu" signal "GND2")
		(14 "In6.Cu" signal "IN3")
		(16 "In7.Cu" signal "GND3")
		(18 "In8.Cu" signal "VCC")
		(20 "In9.Cu" signal "VCC1")
		(22 "In10.Cu" signal "GND4")
		(24 "In11.Cu" signal "IN4")
		(26 "In12.Cu" signal "GND5")
		(28 "In13.Cu" signal "IN5")
		(30 "In14.Cu" signal "GND6")
		(32 "In15.Cu" signal "IN6")
		(34 "In16.Cu" signal "GND7")
		(2 "B.Cu" signal "BOTTOM")
		(9 "F.Adhes" user "F.Adhesive")
		(11 "B.Adhes" user "B.Adhesive")
		(13 "F.Paste" user "Package Geometry/Pastemask Top")
		(15 "B.Paste" user "Package Geometry/Pastemask Bottom")
		(5 "F.SilkS" user "Ref Des/Silkscreen Top")
		(7 "B.SilkS" user "Ref Des/Silkscreen Bottom")
		(1 "F.Mask" user "Board Geometry/Soldermask Top")
		(3 "B.Mask" user "Board Geometry/Soldermask Bottom")
		(17 "Dwgs.User" user "User.Drawings")
		(19 "Cmts.User" user "User.Comments")
		(21 "Eco1.User" user "User.Eco1")
		(23 "Eco2.User" user "User.Eco2")
		(25 "Edge.Cuts" user "Board Geometry/Outline")
		(27 "Margin" user)
		(31 "F.CrtYd" user "Package Geometry/Place Bound Top")
		(29 "B.CrtYd" user "Package Geometry/Place Bound Bottom")
		(35 "F.Fab" user "Ref Des/Assembly Top")
		(33 "B.Fab" user "Ref Des/Assembly Bottom")
	)
	(footprint ""
		(layer "F.Cu")
		(at 185.22188 -130.266948 -90)
		(property "Reference" "R272"
			(at 0 0 270)
			(layer "F.SilkS")
			(hide yes)
			(effects
				(font
					(size 1.27 1.27)
				)
			)
		)
		(property "Value" ""
			(at 0 0 270)
			(layer "F.Fab")
			(effects
				(font
					(size 1.27 1.27)
				)
			)
		)
		(duplicate_pad_numbers_are_jumpers no)
		(fp_line
			(start -0.7874 0.4064)
			(end -0.7874 -0.4064)
			(stroke
				(width 0.1524)
				(type default)
			)
			(layer "F.SilkS")
		)
		(fp_line
			(start 0.7874 0.4064)
			(end -0.7874 0.4064)
			(stroke
				(width 0.1524)
				(type default)
			)
			(layer "F.SilkS")
		)
		(fp_line
			(start -0.7874 -0.4064)
			(end 0.7874 -0.4064)
			(stroke
				(width 0.1524)
				(type default)
			)
			(layer "F.SilkS")
		)
		(fp_line
			(start 0.7874 -0.4064)
			(end 0.7874 0.4064)
			(stroke
				(width 0.1524)
				(type default)
			)
			(layer "F.SilkS")
		)
		(fp_line
			(start -0.67945 0.3048)
			(end -0.67945 -0.305054)
			(stroke
				(width 0.1)
				(type default)
			)
			(layer "F.Fab")
		)
		(fp_line
			(start -0.12065 0.3048)
			(end -0.67945 0.3048)
			(stroke
				(width 0.1)
				(type default)
			)
			(layer "F.Fab")
		)
		(fp_line
			(start 0.120396 0.3048)
			(end 0.120396 0.2794)
			(stroke
				(width 0.1)
				(type default)
			)
			(layer "F.Fab")
		)
		(fp_line
			(start 0.67945 0.3048)
			(end 0.120396 0.3048)
			(stroke
				(width 0.1)
				(type default)
			)
			(layer "F.Fab")
		)
		(fp_line
			(start -0.12065 0.2794)
			(end -0.12065 0.3048)
			(stroke
				(width 0.1)
				(type default)
			)
			(layer "F.Fab")
		)
		(fp_line
			(start 0.120396 0.2794)
			(end -0.12065 0.2794)
			(stroke
				(width 0.1)
				(type default)
			)
			(layer "F.Fab")
		)
		(fp_line
			(start -0.12065 -0.2794)
			(end 0.12065 -0.2794)
			(stroke
				(width 0.1)
				(type default)
			)
			(layer "F.Fab")
		)
		(fp_line
			(start 0.12065 -0.2794)
			(end 0.12065 -0.3048)
			(stroke
				(width 0.1)
				(type default)
			)
			(layer "F.Fab")
		)
		(fp_line
			(start 0.12065 -0.3048)
			(end 0.67945 -0.3048)
			(stroke
				(width 0.1)
				(type default)
			)
			(layer "F.Fab")
		)
		(fp_line
			(start 0.67945 -0.3048)
			(end 0.67945 0.3048)
			(stroke
				(width 0.1)
				(type default)
			)
			(layer "F.Fab")
		)
		(fp_line
			(start -0.67945 -0.305054)
			(end -0.12065 -0.305054)
			(stroke
				(width 0.1)
				(type default)
			)
			(layer "F.Fab")
		)
		(fp_line
			(start -0.12065 -0.305054)
			(end -0.12065 -0.2794)
			(stroke
				(width 0.1)
				(type default)
			)
			(layer "F.Fab")
		)
		(pad "1" smd circle
			(at -0.40005 0 270)
			(size 0 0)
			(layers "F.Cu" "F.Mask" "F.Paste")
			(net "P3V3_AUX")
		)
		(pad "2" smd circle
			(at 0.40005 0 270)
			(size 0 0)
			(layers "F.Cu" "F.Mask" "F.Paste")
			(net "FM_CPU1_PKGID2")
		)
	)
	(footprint ""
		(layer "F.Cu")
		(at 146.12874 -33.157668)
		(property "Reference" "U244"
			(at 0.11684 1.95961 0)
			(unlocked yes)
			(layer "F.SilkS")
			(effects
				(font
					(size 0.7874 0.5842)
					(thickness 0.1524)
				)
			)
		)
		(property "Value" ""
			(at 0 0 0)
			(layer "F.Fab")
			(effects
				(font
					(size 1.27 1.27)
				)
			)
		)
		(duplicate_pad_numbers_are_jumpers no)
		(fp_line
			(start -1.7272 1.1176)
			(end -1.7272 -1.1176)
			(stroke
				(width 0.1524)
				(type default)
			)
			(layer "F.SilkS")
		)
		(fp_line
			(start -0.254 -1.1176)
			(end -1.7272 -1.1176)
			(stroke
				(width 0.1524)
				(type default)
			)
			(layer "F.SilkS")
		)
		(fp_line
			(start 0 -0.7366)
			(end -0.254 -1.1176)
			(stroke
				(width 0.1524)
				(type default)
			)
			(layer "F.SilkS")
		)
		(fp_line
			(start 0.254 -1.1176)
			(end 0 -0.7366)
			(stroke
				(width 0.1524)
				(type default)
			)
			(layer "F.SilkS")
		)
		(fp_line
			(start 1.7272 -1.1176)
			(end 0.254 -1.1176)
			(stroke
				(width 0.1524)
				(type default)
			)
			(layer "F.SilkS")
		)
		(fp_line
			(start 1.7272 -1.1176)
			(end 1.7272 1.1176)
			(stroke
				(width 0.1524)
				(type default)
			)
			(layer "F.SilkS")
		)
		(fp_line
			(start 1.7272 1.1176)
			(end -1.7272 1.1176)
			(stroke
				(width 0.1524)
				(type default)
			)
			(layer "F.SilkS")
		)
		(fp_poly
			(pts
				(xy -1.633474 -2.05994) (xy -0.871474 -2.05994) (xy -1.252474 -1.29794)
			)
			(stroke
				(width 0)
				(type default)
			)
			(fill yes)
			(layer "F.SilkS")
		)
		(fp_line
			(start -1.5748 -1.1176)
			(end -1.5748 1.1176)
			(stroke
				(width 0.1)
				(type default)
			)
			(layer "F.Fab")
		)
		(fp_line
			(start -1.5748 1.1176)
			(end 1.5748 1.1176)
			(stroke
				(width 0.1)
				(type default)
			)
			(layer "F.Fab")
		)
		(fp_line
			(start 1.5748 -1.1176)
			(end -1.5748 -1.1176)
			(stroke
				(width 0.1)
				(type default)
			)
			(layer "F.Fab")
		)
		(fp_line
			(start 1.5748 1.1176)
			(end 1.5748 -1.1176)
			(stroke
				(width 0.1)
				(type default)
			)
			(layer "F.Fab")
		)
		(fp_poly
			(pts
				(xy -1.9558 -0.649986) (xy -2.7178 -0.268986) (xy -2.7178 -1.030986)
			)
			(stroke
				(width 0)
				(type default)
			)
			(fill yes)
			(layer "F.Fab")
		)
		(pad "1" smd rect
			(at -0.999998 -0.649986 270)
			(size 0.3556 1.1176)
			(layers "F.Cu" "F.Mask" "F.Paste")
			(net "OCP_SFF_NOT_PRSNT_RBT_ARB_IN")
		)
		(pad "2" smd rect
			(at -0.999998 0 270)
			(size 0.3556 1.1176)
			(layers "F.Cu" "F.Mask" "F.Paste")
			(net "GND")
		)
		(pad "3" smd rect
			(at -0.999998 0.649986 270)
			(size 0.3556 1.1176)
			(layers "F.Cu" "F.Mask" "F.Paste")
			(net "OCP_SFF_RBT_ARB_IN")
		)
		(pad "4" smd rect
			(at 0.999998 0.649986 270)
			(size 0.3556 1.1176)
			(layers "F.Cu" "F.Mask" "F.Paste")
			(net "OCP_SFF_RBT_ARB_IN_MUX1_R")
		)
		(pad "5" smd rect
			(at 0.999998 0 270)
			(size 0.3556 1.1176)
			(layers "F.Cu" "F.Mask" "F.Paste")
			(net "P3V3_AUX")
		)
		(pad "6" smd rect
			(at 0.999998 -0.649986 270)
			(size 0.3556 1.1176)
			(layers "F.Cu" "F.Mask" "F.Paste")
			(net "OCP_SFF_PRSNT_ALL_R3_N")
		)
	)
)
